(kicad_pcb
	(version 20241229)
	(generator "pcbnew")
	(generator_version "9.0")
	(general
		(thickness 1.61)
		(legacy_teardrops no)
	)
	(paper "A3")
	(title_block
		(title "RDIMM DDR5 Tester")
		(date "2026-05-21")
		(rev "2.2.0")
		(company "Antmicro")
		(comment 9 "footprints 460-463 of 796")
	)
	(layers
		(0 "F.Cu" signal)
		(4 "In1.Cu" power)
		(6 "In2.Cu" mixed)
		(8 "In3.Cu" power)
		(10 "In4.Cu" mixed)
		(12 "In5.Cu" power)
		(14 "In6.Cu" mixed)
		(16 "In7.Cu" power)
		(18 "In8.Cu" power)
		(20 "In9.Cu" mixed)
		(22 "In10.Cu" power)
		(2 "B.Cu" signal)
		(9 "F.Adhes" user "F.Adhesive")
		(11 "B.Adhes" user "B.Adhesive")
		(13 "F.Paste" user)
		(15 "B.Paste" user)
		(5 "F.SilkS" user "F.Silkscreen")
		(7 "B.SilkS" user "B.Silkscreen")
		(1 "F.Mask" user)
		(3 "B.Mask" user)
		(17 "Dwgs.User" user "User.Drawings")
		(19 "Cmts.User" user "User.Comments")
		(21 "Eco1.User" user "User.Eco1")
		(23 "Eco2.User" user "User.Eco2")
		(25 "Edge.Cuts" user)
		(27 "Margin" user)
		(31 "F.CrtYd" user "F.Courtyard")
		(29 "B.CrtYd" user "B.Courtyard")
		(35 "F.Fab" user)
		(33 "B.Fab" user)
	)
	(footprint "antmicro-footprints:C_0402_1005Metric_EIA"
		(layer "B.Cu")
		(at 192 154.5 -90)
		(descr "Capacitor SMD 0402 (1005 Metric), square (rectangular) end terminal, IPC_7351 nominal, (Body size source: IPC-SM-782 page 76, https://www.pcb-3d.com/wordpress/wp-content/uploads/ipc-sm-782a_amendment_1_and_2.pdf)")
		(tags "capacitor 0402")
		(property "Reference" "C75"
			(at -12.125 30.65 90)
			(layer "B.SilkS")
			(effects
				(font
					(size 0.7 0.7)
					(thickness 0.15)
				)
				(justify left bottom mirror)
			)
		)
		(property "Value" "C_1u_25V_0402"
			(at 0 -1.169 90)
			(layer "B.Fab")
			(effects
				(font
					(size 0.7 0.7)
					(thickness 0.15)
				)
				(justify left bottom mirror)
			)
		)
		(property "Datasheet" "https://www.murata.com/products/productdetail?partno=GRM155R61E105KE11%23"
			(at 0 0 270)
			(layer "F.Fab")
			(hide yes)
			(effects
				(font
					(size 1.27 1.27)
					(thickness 0.15)
				)
			)
		)
		(property "MPN" "GRM155R61E105KE11J"
			(at 0 0 270)
			(unlocked yes)
			(layer "B.Fab")
			(hide yes)
			(effects
				(font
					(size 1 1)
					(thickness 0.15)
				)
				(justify mirror)
			)
		)
		(property "Manufacturer" "Murata"
			(at 0 0 270)
			(unlocked yes)
			(layer "B.Fab")
			(hide yes)
			(effects
				(font
					(size 1 1)
					(thickness 0.15)
				)
				(justify mirror)
			)
		)
		(property "License" "Apache-2.0"
			(at 0 0 270)
			(unlocked yes)
			(layer "B.Fab")
			(hide yes)
			(effects
				(font
					(size 1 1)
					(thickness 0.15)
				)
				(justify mirror)
			)
		)
		(property "Author" "Antmicro"
			(at 0 0 270)
			(unlocked yes)
			(layer "B.Fab")
			(hide yes)
			(effects
				(font
					(size 1 1)
					(thickness 0.15)
				)
				(justify mirror)
			)
		)
		(property "Val" "1u"
			(at 0 0 270)
			(unlocked yes)
			(layer "B.Fab")
			(hide yes)
			(effects
				(font
					(size 1 1)
					(thickness 0.15)
				)
				(justify mirror)
			)
		)
		(property "Voltage" "25V"
			(at 0 0 270)
			(unlocked yes)
			(layer "B.Fab")
			(hide yes)
			(effects
				(font
					(size 1 1)
					(thickness 0.15)
				)
				(justify mirror)
			)
		)
		(property "Dielectric" "X5R"
			(at 0 0 270)
			(unlocked yes)
			(layer "B.Fab")
			(hide yes)
			(effects
				(font
					(size 1 1)
					(thickness 0.15)
				)
				(justify mirror)
			)
		)
		(sheetname "/FPGA power/")
		(sheetfile "fpga-power.kicad_sch")
		(attr smd)
		(fp_rect
			(start -0.95 0.45)
			(end 0.95 -0.45)
			(stroke
				(width 0.05)
				(type default)
			)
			(fill no)
			(layer "B.CrtYd")
		)
		(fp_line
			(start -0.5 0.25)
			(end 0.498 0.25)
			(stroke
				(width 0.15)
				(type solid)
			)
			(layer "B.Fab")
		)
		(fp_line
			(start 0.498 0.25)
			(end 0.498 -0.248)
			(stroke
				(width 0.15)
				(type solid)
			)
			(layer "B.Fab")
		)
		(fp_line
			(start -0.5 -0.248)
			(end -0.5 0.25)
			(stroke
				(width 0.15)
				(type solid)
			)
			(layer "B.Fab")
		)
		(fp_line
			(start 0.498 -0.248)
			(end -0.5 -0.248)
			(stroke
				(width 0.15)
				(type solid)
			)
			(layer "B.Fab")
		)
		(fp_text user "Author: Antmicro"
			(at -0.9656 -5.569 90)
			(layer "B.Fab")
			(effects
				(font
					(size 0.7 0.7)
					(thickness 0.15)
				)
				(justify left bottom mirror)
			)
		)
		(fp_text user "License: Apache-2.0"
			(at -0.9656 -4.369 90)
			(layer "B.Fab")
			(effects
				(font
					(size 0.7 0.7)
					(thickness 0.15)
				)
				(justify left bottom mirror)
			)
		)
		(fp_text user "${REFERENCE}"
			(at -0.9656 -3.169 90)
			(layer "B.Fab")
			(effects
				(font
					(size 0.7 0.7)
					(thickness 0.15)
				)
				(justify left bottom mirror)
			)
		)
		(pad "1" smd roundrect
			(at -0.5 0 180)
			(size 0.6 0.6)
			(layers "B.Cu" "B.Mask" "B.Paste")
			(roundrect_rratio 0.25)
			(net 1 "GND")
			(pintype "passive")
		)
		(pad "2" smd roundrect
			(at 0.498 0 270)
			(size 0.6 0.6)
			(layers "B.Cu" "B.Mask" "B.Paste")
			(roundrect_rratio 0.25)
			(net 553 "+0V85")
			(pintype "passive")
		)
	)
	(footprint "antmicro-footprints:C_0402_1005Metric"
		(layer "B.Cu")
		(at 119.075 159.45 -90)
		(descr "Capacitor SMD 0402")
		(tags "capacitor SMD 0402")
		(property "Reference" "C299"
			(at 0.9 -0.525 90)
			(layer "B.SilkS")
			(effects
				(font
					(size 0.7 0.7)
					(thickness 0.15)
				)
				(justify left bottom mirror)
			)
		)
		(property "Value" "C_100n_0402"
			(at -1.022927 -2.155213 90)
			(layer "B.Fab")
			(effects
				(font
					(size 0.7 0.7)
					(thickness 0.15)
				)
				(justify left bottom mirror)
			)
		)
		(property "Datasheet" "https://www.murata.com/products/productdetail?partno=GRM155R61H104KE14%23"
			(at 0 0 270)
			(layer "F.Fab")
			(hide yes)
			(effects
				(font
					(size 1.27 1.27)
					(thickness 0.15)
				)
			)
		)
		(property "MPN" "GRM155R61H104KE14D"
			(at 0 0 270)
			(unlocked yes)
			(layer "B.Fab")
			(hide yes)
			(effects
				(font
					(size 1 1)
					(thickness 0.15)
				)
				(justify mirror)
			)
		)
		(property "Manufacturer" "Murata"
			(at 0 0 270)
			(unlocked yes)
			(layer "B.Fab")
			(hide yes)
			(effects
				(font
					(size 1 1)
					(thickness 0.15)
				)
				(justify mirror)
			)
		)
		(property "License" "Apache-2.0"
			(at 0 0 270)
			(unlocked yes)
			(layer "B.Fab")
			(hide yes)
			(effects
				(font
					(size 1 1)
					(thickness 0.15)
				)
				(justify mirror)
			)
		)
		(property "Author" "Antmicro"
			(at 0 0 270)
			(unlocked yes)
			(layer "B.Fab")
			(hide yes)
			(effects
				(font
					(size 1 1)
					(thickness 0.15)
				)
				(justify mirror)
			)
		)
		(property "Val" "100n"
			(at 0 0 270)
			(unlocked yes)
			(layer "B.Fab")
			(hide yes)
			(effects
				(font
					(size 1 1)
					(thickness 0.15)
				)
				(justify mirror)
			)
		)
		(property "Voltage" "50V"
			(at 0 0 270)
			(unlocked yes)
			(layer "B.Fab")
			(hide yes)
			(effects
				(font
					(size 1 1)
					(thickness 0.15)
				)
				(justify mirror)
			)
		)
		(property "Dielectric" "X5R"
			(at 0 0 270)
			(unlocked yes)
			(layer "B.Fab")
			(hide yes)
			(effects
				(font
					(size 1 1)
					(thickness 0.15)
				)
				(justify mirror)
			)
		)
		(sheetname "/HDMI + SD Card/")
		(sheetfile "hdmi-sd-card.kicad_sch")
		(attr smd)
		(fp_rect
			(start -0.925 0.47)
			(end 0.925 -0.47)
			(stroke
				(width 0.05)
				(type default)
			)
			(fill no)
			(layer "B.CrtYd")
		)
		(fp_line
			(start -0.494 0.25)
			(end 0.504 0.25)
			(stroke
				(width 0.15)
				(type solid)
			)
			(layer "B.Fab")
		)
		(fp_line
			(start 0.504 0.25)
			(end 0.504 -0.248)
			(stroke
				(width 0.15)
				(type solid)
			)
			(layer "B.Fab")
		)
		(fp_line
			(start -0.494 -0.248)
			(end -0.494 0.25)
			(stroke
				(width 0.15)
				(type solid)
			)
			(layer "B.Fab")
		)
		(fp_line
			(start 0.504 -0.248)
			(end -0.494 -0.248)
			(stroke
				(width 0.15)
				(type solid)
			)
			(layer "B.Fab")
		)
		(fp_text user "License: Apache-2.0"
			(at -0.939 -5.799 90)
			(layer "B.Fab")
			(effects
				(font
					(size 0.7 0.7)
					(thickness 0.15)
				)
				(justify left bottom mirror)
			)
		)
		(fp_text user "Author: Antmicro"
			(at -0.939 -3.399 90)
			(layer "B.Fab")
			(effects
				(font
					(size 0.7 0.7)
					(thickness 0.15)
				)
				(justify left bottom mirror)
			)
		)
		(fp_text user "${REFERENCE}"
			(at -0.939 -4.599 90)
			(layer "B.Fab")
			(effects
				(font
					(size 0.7 0.7)
					(thickness 0.15)
				)
				(justify left bottom mirror)
			)
		)
		(pad "1" smd roundrect
			(at -0.48 0 270)
			(size 0.59 0.64)
			(layers "B.Cu" "B.Mask" "B.Paste")
			(roundrect_rratio 0.25)
			(net 1 "GND")
			(pintype "passive")
		)
		(pad "2" smd roundrect
			(at 0.48 0 270)
			(size 0.59 0.64)
			(layers "B.Cu" "B.Mask" "B.Paste")
			(roundrect_rratio 0.25)
			(net 647 "/HDMI + SD Card/VCCB")
			(pintype "passive")
		)
	)
	(footprint "antmicro-footprints:R_0402_1005Metric"
		(layer "B.Cu")
		(at 240.12 171.425)
		(descr "Resistor SMD 0402")
		(tags "resistor SMD 0402")
		(property "Reference" "R215"
			(at 1.655 0.5 0)
			(layer "B.SilkS")
			(effects
				(font
					(size 0.7 0.7)
					(thickness 0.15)
				)
				(justify right bottom mirror)
			)
		)
		(property "Value" "R_100R_0402"
			(at -1.011843 -1.772047 0)
			(layer "B.Fab")
			(effects
				(font
					(size 0.7 0.7)
					(thickness 0.15)
				)
				(justify right bottom mirror)
			)
		)
		(property "Datasheet" "https://www.bourns.com/docs/product-datasheets/cr.pdf"
			(at 0 0 0)
			(layer "F.Fab")
			(hide yes)
			(effects
				(font
					(size 1.27 1.27)
					(thickness 0.15)
				)
			)
		)
		(property "MPN" "CR0402-FX-1000GLF"
			(at 0 0 0)
			(unlocked yes)
			(layer "B.Fab")
			(hide yes)
			(effects
				(font
					(size 1 1)
					(thickness 0.15)
				)
				(justify mirror)
			)
		)
		(property "Manufacturer" "Bourns"
			(at 0 0 0)
			(unlocked yes)
			(layer "B.Fab")
			(hide yes)
			(effects
				(font
					(size 1 1)
					(thickness 0.15)
				)
				(justify mirror)
			)
		)
		(property "License" "Apache-2.0"
			(at 0 0 0)
			(unlocked yes)
			(layer "B.Fab")
			(hide yes)
			(effects
				(font
					(size 1 1)
					(thickness 0.15)
				)
				(justify mirror)
			)
		)
		(property "Author" "Antmicro"
			(at 0 0 0)
			(unlocked yes)
			(layer "B.Fab")
			(hide yes)
			(effects
				(font
					(size 1 1)
					(thickness 0.15)
				)
				(justify mirror)
			)
		)
		(property "Val" "100R"
			(at 0 0 0)
			(unlocked yes)
			(layer "B.Fab")
			(hide yes)
			(effects
				(font
					(size 1 1)
					(thickness 0.15)
				)
				(justify mirror)
			)
		)
		(property "Tolerance" "1%"
			(at 0 0 0)
			(unlocked yes)
			(layer "B.Fab")
			(hide yes)
			(effects
				(font
					(size 1 1)
					(thickness 0.15)
				)
				(justify mirror)
			)
		)
		(sheetname "/Supply/DC-DC AUX, MGT/")
		(sheetfile "dc-dc-aux-mgt.kicad_sch")
		(attr smd)
		(fp_rect
			(start -0.925 0.47)
			(end 0.925 -0.47)
			(stroke
				(width 0.05)
				(type default)
			)
			(fill no)
			(layer "B.CrtYd")
		)
		(fp_rect
			(start -0.5 0.25)
			(end 0.5 -0.25)
			(stroke
				(width 0.15)
				(type solid)
			)
			(fill no)
			(layer "B.Fab")
		)
		(fp_text user "License: Apache-2.0"
			(at -0.95 -5.169 180)
			(layer "B.Fab")
			(effects
				(font
					(size 0.7 0.7)
					(thickness 0.15)
				)
				(justify left bottom mirror)
			)
		)
		(fp_text user "${REFERENCE}"
			(at -0.95 -3.168 180)
			(layer "B.Fab")
			(effects
				(font
					(size 0.7 0.7)
					(thickness 0.15)
				)
				(justify left bottom mirror)
			)
		)
		(fp_text user "Author: Antmicro"
			(at -0.95 -4.169 180)
			(layer "B.Fab")
			(effects
				(font
					(size 0.7 0.7)
					(thickness 0.15)
				)
				(justify left bottom mirror)
			)
		)
		(pad "1" smd roundrect
			(at -0.48 0)
			(size 0.59 0.64)
			(layers "B.Cu" "B.Mask" "B.Paste")
			(roundrect_rratio 0.25)
			(net 1 "GND")
			(pintype "passive")
		)
		(pad "2" smd roundrect
			(at 0.48 0)
			(size 0.59 0.64)
			(layers "B.Cu" "B.Mask" "B.Paste")
			(roundrect_rratio 0.25)
			(net 735 "Net-(U25-ADDRSEL)")
			(pintype "passive")
		)
	)
	(footprint "antmicro-footprints:SC70-3"
		(layer "B.Cu")
		(at 114.755 115.65 180)
		(property "Reference" "Q8"
			(at -3.355 -0.334 0)
			(layer "B.SilkS")
			(effects
				(font
					(size 0.7 0.7)
					(thickness 0.15)
				)
				(justify left bottom mirror)
			)
		)
		(property "Value" "BSS138PW"
			(at 0 -2.3 0)
			(layer "B.Fab")
			(effects
				(font
					(size 0.7 0.7)
					(thickness 0.15)
				)
				(justify left bottom mirror)
			)
		)
		(property "Datasheet" "https://assets.nexperia.com/documents/data-sheet/BSS138PW.pdf"
			(at 0 0 180)
			(layer "F.Fab")
			(hide yes)
			(effects
				(font
					(size 1.27 1.27)
					(thickness 0.15)
				)
			)
		)
		(property "MPN" "BSS138PW"
			(at 0 0 180)
			(unlocked yes)
			(layer "B.Fab")
			(hide yes)
			(effects
				(font
					(size 1 1)
					(thickness 0.15)
				)
				(justify mirror)
			)
		)
		(property "Manufacturer" "Nexperia"
			(at 0 0 180)
			(unlocked yes)
			(layer "B.Fab")
			(hide yes)
			(effects
				(font
					(size 1 1)
					(thickness 0.15)
				)
				(justify mirror)
			)
		)
		(property "Author" "Antmicro"
			(at 0 0 180)
			(unlocked yes)
			(layer "B.Fab")
			(hide yes)
			(effects
				(font
					(size 1 1)
					(thickness 0.15)
				)
				(justify mirror)
			)
		)
		(property "License" "Apache-2.0"
			(at 0 0 180)
			(unlocked yes)
			(layer "B.Fab")
			(hide yes)
			(effects
				(font
					(size 1 1)
					(thickness 0.15)
				)
				(justify mirror)
			)
		)
		(sheetname "/FPGA banks HD/")
		(sheetfile "fpga-hd-banks.kicad_sch")
		(attr smd)
		(fp_line
			(start 0.627 0.6)
			(end 0.627 0.999)
			(stroke
				(width 0.15)
				(type solid)
			)
			(layer "B.SilkS")
		)
		(fp_line
			(start 0.627 -0.6)
			(end 0.627 -1.001)
			(stroke
				(width 0.15)
				(type solid)
			)
			(layer "B.SilkS")
		)
		(fp_line
			(start -0.3 1)
			(end 0.627 0.999)
			(stroke
				(width 0.15)
				(type solid)
			)
			(layer "B.SilkS")
		)
		(fp_line
			(start -0.3 -1)
			(end 0.627 -1.001)
			(stroke
				(width 0.15)
				(type solid)
			)
			(layer "B.SilkS")
		)
		(fp_line
			(start 1.4 0.4)
			(end 1.4 -0.4)
			(stroke
				(width 0.05)
				(type solid)
			)
			(layer "B.CrtYd")
		)
		(fp_line
			(start 1.4 -0.4)
			(end 0.9 -0.4)
			(stroke
				(width 0.05)
				(type solid)
			)
			(layer "B.CrtYd")
		)
		(fp_line
			(start 0.9 1.3)
			(end 0.9 0.4)
			(stroke
				(width 0.05)
				(type solid)
			)
			(layer "B.CrtYd")
		)
		(fp_line
			(start 0.9 0.4)
			(end 1.4 0.4)
			(stroke
				(width 0.05)
				(type solid)
			)
			(layer "B.CrtYd")
		)
		(fp_line
			(start 0.9 -0.4)
			(end 0.9 -1.3)
			(stroke
				(width 0.05)
				(type solid)
			)
			(layer "B.CrtYd")
		)
		(fp_line
			(start 0.9 -1.3)
			(end -0.9 -1.3)
			(stroke
				(width 0.05)
				(type solid)
			)
			(layer "B.CrtYd")
		)
		(fp_line
			(start -0.9 1.3)
			(end 0.9 1.3)
			(stroke
				(width 0.05)
				(type solid)
			)
			(layer "B.CrtYd")
		)
		(fp_line
			(start -0.9 1.3)
			(end -0.9 1)
			(stroke
				(width 0.05)
				(type solid)
			)
			(layer "B.CrtYd")
		)
		(fp_line
			(start -0.9 1)
			(end -1.4 1)
			(stroke
				(width 0.05)
				(type solid)
			)
			(layer "B.CrtYd")
		)
		(fp_line
			(start -0.9 -1)
			(end -1.4 -1)
			(stroke
				(width 0.05)
				(type solid)
			)
			(layer "B.CrtYd")
		)
		(fp_line
			(start -0.9 -1.3)
			(end -0.9 -1)
			(stroke
				(width 0.05)
				(type solid)
			)
			(layer "B.CrtYd")
		)
		(fp_line
			(start -1.4 -1)
			(end -1.4 1)
			(stroke
				(width 0.05)
				(type solid)
			)
			(layer "B.CrtYd")
		)
		(fp_rect
			(start -0.623 0.999)
			(end 0.627 -1.001)
			(stroke
				(width 0.15)
				(type solid)
			)
			(fill no)
			(layer "B.Fab")
		)
		(fp_text user "License: Apache-2.0"
			(at -1.45 -6.782 0)
			(layer "B.Fab")
			(effects
				(font
					(size 0.7 0.7)
					(thickness 0.15)
				)
				(justify left bottom mirror)
			)
		)
		(fp_text user "${REFERENCE}"
			(at -1.45 -4.783 0)
			(layer "B.Fab")
			(effects
				(font
					(size 0.7 0.7)
					(thickness 0.15)
				)
				(justify left bottom mirror)
			)
		)
		(fp_text user "Author: Antmicro"
			(at -1.45 -5.782 0)
			(layer "B.Fab")
			(effects
				(font
					(size 0.7 0.7)
					(thickness 0.15)
				)
				(justify left bottom mirror)
			)
		)
		(pad "1" smd rect
			(at -1.051 0.65 90)
			(size 0.6 0.6)
			(layers "B.Cu" "B.Mask" "B.Paste")
			(net 697 "/FPGA banks HD/USR_LED1")
			(pinfunction "G")
			(pintype "passive")
		)
		(pad "2" smd rect
			(at -1.051 -0.65 90)
			(size 0.6 0.6)
			(layers "B.Cu" "B.Mask" "B.Paste")
			(net 1 "GND")
			(pinfunction "S")
			(pintype "passive")
		)
		(pad "3" smd rect
			(at 1.05 0 90)
			(size 0.6 0.6)
			(layers "B.Cu" "B.Mask" "B.Paste")
			(net 276 "Net-(Q8-D)")
			(pinfunction "D")
			(pintype "passive")
		)
	)
)
